(kicad_pcb
	(version 20260206)
	(generator "pcbnew")
	(generator_version "10.0")
	(general
		(thickness 1.6)
		(legacy_teardrops no)
	)
	(paper "A4")
	(title_block
		(title "fcb — Lightning_FCB_BRD.brd")
		(comment 1 "Lightning (Wiwynn / Facebook NVMe JBOF) / footprints 283-289 of 495")
	)
	(layers
		(0 "F.Cu" signal "TOP")
		(4 "In1.Cu" signal "L2GND")
		(6 "In2.Cu" signal "L3VCC")
		(2 "B.Cu" signal "BOTTOM")
		(9 "F.Adhes" user "F.Adhesive")
		(11 "B.Adhes" user "B.Adhesive")
		(13 "F.Paste" user "Package Geometry/Pastemask Top")
		(15 "B.Paste" user "Package Geometry/Pastemask Bottom")
		(5 "F.SilkS" user "Ref Des/Silkscreen Top")
		(7 "B.SilkS" user "Ref Des/Silkscreen Bottom")
		(1 "F.Mask" user "Board Geometry/Soldermask Top")
		(3 "B.Mask" user "Board Geometry/Soldermask Bottom")
		(17 "Dwgs.User" user "User.Drawings")
		(19 "Cmts.User" user "User.Comments")
		(21 "Eco1.User" user "User.Eco1")
		(23 "Eco2.User" user "User.Eco2")
		(25 "Edge.Cuts" user "Board Geometry/Outline")
		(27 "Margin" user)
		(31 "F.CrtYd" user "Package Geometry/Place Bound Top")
		(29 "B.CrtYd" user "Package Geometry/Place Bound Bottom")
		(35 "F.Fab" user "Ref Des/Assembly Top")
		(33 "B.Fab" user "Ref Des/Assembly Bottom")
	)
	(footprint ""
		(layer "F.Cu")
		(at 37.338 -144.272 -90)
		(property "Reference" "PR111"
			(at 0 0 270)
			(layer "F.SilkS")
			(hide yes)
			(effects
				(font
					(size 1.27 1.27)
				)
			)
		)
		(property "Value" "178KR2F-GP"
			(at 0.064008 -3.993896 270)
			(unlocked yes)
			(layer "F.Fab")
			(hide yes)
			(effects
				(font
					(size 1.016 1.016)
					(thickness 0.1524)
				)
			)
		)
		(property "Device Type" "R402H16"
			(at 0.064008 -5.517896 270)
			(unlocked yes)
			(layer "F.Fab")
			(hide yes)
			(effects
				(font
					(size 1.016 1.016)
					(thickness 0.1524)
				)
			)
		)
		(duplicate_pad_numbers_are_jumpers no)
		(fp_line
			(start -0.508 -0.9398)
			(end -0.508 0.9398)
			(stroke
				(width 0.1524)
				(type default)
			)
			(layer "F.SilkS")
		)
		(fp_line
			(start 0.508 -0.9398)
			(end -0.508 -0.9398)
			(stroke
				(width 0.1524)
				(type default)
			)
			(layer "F.SilkS")
		)
		(fp_rect
			(start -0.508 0.9398)
			(end 0.508 -0.9398)
			(stroke
				(width 0)
				(type default)
			)
			(fill no)
			(layer "F.CrtYd")
		)
		(fp_rect
			(start -0.508 0.9398)
			(end 0.508 -0.9398)
			(stroke
				(width 0)
				(type default)
			)
			(fill no)
			(layer "F.Fab")
		)
		(pad "1" smd custom
			(at 0 -0.4445 270)
			(size 0.1397 0.1397)
			(layers "F.Cu" "F.Mask" "F.Paste")
			(net "P12VL_2490_VREF")
			(options
				(clearance outline)
				(anchor circle)
			)
			(primitives
				(gr_poly
					(pts
						(arc
							(start -0.1778 -0.2794)
							(mid -0.249642 -0.249642)
							(end -0.2794 -0.1778)
						)
						(arc
							(start -0.2794 0.1778)
							(mid -0.249642 0.249642)
							(end -0.1778 0.2794)
						)
						(arc
							(start 0.1778 0.2794)
							(mid 0.249642 0.249642)
							(end 0.2794 0.1778)
						)
						(arc
							(start 0.2794 -0.1778)
							(mid 0.249642 -0.249642)
							(end 0.1778 -0.2794)
						)
					)
					(width 0)
					(fill yes)
				)
			)
		)
		(pad "2" smd custom
			(at 0 0.4445 270)
			(size 0.1397 0.1397)
			(layers "F.Cu" "F.Mask" "F.Paste")
			(net "P12VL_2490_PROG")
			(options
				(clearance outline)
				(anchor circle)
			)
			(primitives
				(gr_poly
					(pts
						(arc
							(start -0.1778 -0.2794)
							(mid -0.249642 -0.249642)
							(end -0.2794 -0.1778)
						)
						(arc
							(start -0.2794 0.1778)
							(mid -0.249642 0.249642)
							(end -0.1778 0.2794)
						)
						(arc
							(start 0.1778 0.2794)
							(mid 0.249642 0.249642)
							(end 0.2794 0.1778)
						)
						(arc
							(start 0.2794 -0.1778)
							(mid 0.249642 -0.249642)
							(end 0.1778 -0.2794)
						)
					)
					(width 0)
					(fill yes)
				)
			)
		)
	)
	(footprint ""
		(layer "F.Cu")
		(at 24.4602 -142.367)
		(property "Reference" "PC96"
			(at 0 0 0)
			(layer "F.SilkS")
			(hide yes)
			(effects
				(font
					(size 1.27 1.27)
				)
			)
		)
		(property "Value" "SCD1U50V3KX-GP"
			(at 0 -2.8194 0)
			(unlocked yes)
			(layer "F.Fab")
			(hide yes)
			(effects
				(font
					(size 1.016 1.016)
					(thickness 0.1524)
				)
			)
		)
		(property "Device Type" "C603H36"
			(at 0 -4.3434 0)
			(unlocked yes)
			(layer "F.Fab")
			(hide yes)
			(effects
				(font
					(size 1.016 1.016)
					(thickness 0.1524)
				)
			)
		)
		(duplicate_pad_numbers_are_jumpers no)
		(fp_line
			(start 0.508 0)
			(end -0.508 0)
			(stroke
				(width 0.2032)
				(type default)
			)
			(layer "F.SilkS")
		)
		(fp_rect
			(start -0.5842 1.3335)
			(end 0.5842 -1.3335)
			(stroke
				(width 0)
				(type default)
			)
			(fill no)
			(layer "F.CrtYd")
		)
		(fp_rect
			(start -0.5842 1.3335)
			(end 0.5842 -1.3335)
			(stroke
				(width 0)
				(type default)
			)
			(fill no)
			(layer "F.Fab")
		)
		(pad "1" smd custom
			(at 0 -0.762)
			(size 0.2159 0.2159)
			(layers "F.Cu" "F.Mask" "F.Paste")
			(net "P12VU_2490_EN_2")
			(options
				(clearance outline)
				(anchor circle)
			)
			(primitives
				(gr_poly
					(pts
						(arc
							(start -0.3302 -0.4318)
							(mid -0.402042 -0.402042)
							(end -0.4318 -0.3302)
						)
						(arc
							(start -0.4318 0.3302)
							(mid -0.402042 0.402042)
							(end -0.3302 0.4318)
						)
						(arc
							(start 0.3302 0.4318)
							(mid 0.402042 0.402042)
							(end 0.4318 0.3302)
						)
						(arc
							(start 0.4318 -0.3302)
							(mid 0.402042 -0.402042)
							(end 0.3302 -0.4318)
						)
					)
					(width 0)
					(fill yes)
				)
			)
		)
		(pad "2" smd custom
			(at 0 0.762)
			(size 0.2159 0.2159)
			(layers "F.Cu" "F.Mask" "F.Paste")
			(net "GND")
			(options
				(clearance outline)
				(anchor circle)
			)
			(primitives
				(gr_poly
					(pts
						(arc
							(start -0.3302 -0.4318)
							(mid -0.402042 -0.402042)
							(end -0.4318 -0.3302)
						)
						(arc
							(start -0.4318 0.3302)
							(mid -0.402042 0.402042)
							(end -0.3302 0.4318)
						)
						(arc
							(start 0.3302 0.4318)
							(mid 0.402042 0.402042)
							(end 0.4318 0.3302)
						)
						(arc
							(start 0.4318 -0.3302)
							(mid 0.402042 -0.402042)
							(end 0.3302 -0.4318)
						)
					)
					(width 0)
					(fill yes)
				)
			)
		)
	)
	(footprint ""
		(layer "F.Cu")
		(at 33.401 -362.7882 -90)
		(property "Reference" "PR39"
			(at 0 0 270)
			(layer "F.SilkS")
			(hide yes)
			(effects
				(font
					(size 1.27 1.27)
				)
			)
		)
		(property "Value" "5K1R2F-2-GP"
			(at 0.064008 -3.993896 270)
			(unlocked yes)
			(layer "F.Fab")
			(hide yes)
			(effects
				(font
					(size 1.016 1.016)
					(thickness 0.1524)
				)
			)
		)
		(property "Device Type" "R402H16"
			(at 0.064008 -5.517896 270)
			(unlocked yes)
			(layer "F.Fab")
			(hide yes)
			(effects
				(font
					(size 1.016 1.016)
					(thickness 0.1524)
				)
			)
		)
		(duplicate_pad_numbers_are_jumpers no)
		(fp_line
			(start -0.508 -0.9398)
			(end -0.508 0.9398)
			(stroke
				(width 0.1524)
				(type default)
			)
			(layer "F.SilkS")
		)
		(fp_line
			(start 0.508 -0.9398)
			(end -0.508 -0.9398)
			(stroke
				(width 0.1524)
				(type default)
			)
			(layer "F.SilkS")
		)
		(fp_rect
			(start -0.508 0.9398)
			(end 0.508 -0.9398)
			(stroke
				(width 0)
				(type default)
			)
			(fill no)
			(layer "F.CrtYd")
		)
		(fp_rect
			(start -0.508 0.9398)
			(end 0.508 -0.9398)
			(stroke
				(width 0)
				(type default)
			)
			(fill no)
			(layer "F.Fab")
		)
		(pad "1" smd custom
			(at 0 -0.4445 270)
			(size 0.1397 0.1397)
			(layers "F.Cu" "F.Mask" "F.Paste")
			(net "TEMP_ALM#_REVERSE_R")
			(options
				(clearance outline)
				(anchor circle)
			)
			(primitives
				(gr_poly
					(pts
						(arc
							(start -0.1778 -0.2794)
							(mid -0.249642 -0.249642)
							(end -0.2794 -0.1778)
						)
						(arc
							(start -0.2794 0.1778)
							(mid -0.249642 0.249642)
							(end -0.1778 0.2794)
						)
						(arc
							(start 0.1778 0.2794)
							(mid 0.249642 0.249642)
							(end 0.2794 0.1778)
						)
						(arc
							(start 0.2794 -0.1778)
							(mid 0.249642 -0.249642)
							(end 0.1778 -0.2794)
						)
					)
					(width 0)
					(fill yes)
				)
			)
		)
		(pad "2" smd custom
			(at 0 0.4445 270)
			(size 0.1397 0.1397)
			(layers "F.Cu" "F.Mask" "F.Paste")
			(net "GND")
			(options
				(clearance outline)
				(anchor circle)
			)
			(primitives
				(gr_poly
					(pts
						(arc
							(start -0.1778 -0.2794)
							(mid -0.249642 -0.249642)
							(end -0.2794 -0.1778)
						)
						(arc
							(start -0.2794 0.1778)
							(mid -0.249642 0.249642)
							(end -0.1778 0.2794)
						)
						(arc
							(start 0.1778 0.2794)
							(mid 0.249642 0.249642)
							(end 0.2794 0.1778)
						)
						(arc
							(start 0.2794 -0.1778)
							(mid 0.249642 -0.249642)
							(end 0.1778 -0.2794)
						)
					)
					(width 0)
					(fill yes)
				)
			)
		)
	)
	(footprint ""
		(layer "F.Cu")
		(at 37.338 -184.531 180)
		(property "Reference" "PC1262"
			(at 0 0 180)
			(layer "F.SilkS")
			(hide yes)
			(effects
				(font
					(size 1.27 1.27)
				)
			)
		)
		(property "Value" "SC10U16V6KX-2GP"
			(at -0.0762 -5.1308 180)
			(unlocked yes)
			(layer "F.Fab")
			(hide yes)
			(effects
				(font
					(size 1.016 1.016)
					(thickness 0.1524)
				)
			)
		)
		(property "Device Type" "C1206H71"
			(at -0.127 -6.6548 180)
			(unlocked yes)
			(layer "F.Fab")
			(hide yes)
			(effects
				(font
					(size 1.016 1.016)
					(thickness 0.1524)
				)
			)
		)
		(duplicate_pad_numbers_are_jumpers no)
		(fp_line
			(start 1.016 2.2352)
			(end -1.016 2.2352)
			(stroke
				(width 0.1524)
				(type default)
			)
			(layer "F.SilkS")
		)
		(fp_line
			(start 1.016 0.8382)
			(end 1.016 2.2352)
			(stroke
				(width 0.1524)
				(type default)
			)
			(layer "F.SilkS")
		)
		(fp_line
			(start 1.016 -2.2352)
			(end 1.016 -0.8382)
			(stroke
				(width 0.1524)
				(type default)
			)
			(layer "F.SilkS")
		)
		(fp_line
			(start -1.016 2.2352)
			(end -1.016 0.8382)
			(stroke
				(width 0.1524)
				(type default)
			)
			(layer "F.SilkS")
		)
		(fp_line
			(start -1.016 -0.8382)
			(end -1.016 -2.2352)
			(stroke
				(width 0.1524)
				(type default)
			)
			(layer "F.SilkS")
		)
		(fp_line
			(start -1.016 -2.2352)
			(end 1.016 -2.2352)
			(stroke
				(width 0.1524)
				(type default)
			)
			(layer "F.SilkS")
		)
		(fp_rect
			(start -1.0922 2.3114)
			(end 1.0922 -2.3114)
			(stroke
				(width 0)
				(type default)
			)
			(fill no)
			(layer "F.CrtYd")
		)
		(fp_poly
			(pts
				(xy 1.0922 -2.3114) (xy 1.0922 2.3114) (xy -1.0922 2.3114) (xy -1.0922 -2.3114)
			)
			(stroke
				(width 0)
				(type default)
			)
			(fill no)
			(layer "F.Fab")
		)
		(pad "1" smd rect
			(at 0 -1.397 180)
			(size 1.651 1.27)
			(layers "F.Cu" "F.Mask" "F.Paste")
			(net "P3V3_AUX")
		)
		(pad "2" smd rect
			(at 0 1.397 180)
			(size 1.651 1.27)
			(layers "F.Cu" "F.Mask" "F.Paste")
			(net "GND")
		)
	)
	(footprint ""
		(layer "F.Cu")
		(at 12.446 -394.081 -90)
		(property "Reference" "TC12"
			(at 0 0 270)
			(layer "F.SilkS")
			(hide yes)
			(effects
				(font
					(size 1.27 1.27)
				)
			)
		)
		(property "Value" "ST15U25VDM-1-GP"
			(at 0 -9.6012 270)
			(unlocked yes)
			(layer "F.Fab")
			(hide yes)
			(effects
				(font
					(size 1.016 1.016)
					(thickness 0.1524)
				)
			)
		)
		(property "Device Type" "CT7343H79"
			(at 0 -11.1252 270)
			(unlocked yes)
			(layer "F.Fab")
			(hide yes)
			(effects
				(font
					(size 1.016 1.016)
					(thickness 0.1524)
				)
			)
		)
		(duplicate_pad_numbers_are_jumpers no)
		(fp_line
			(start -2.286 4.8768)
			(end -2.286 2.032)
			(stroke
				(width 0.1524)
				(type default)
			)
			(layer "F.SilkS")
		)
		(fp_line
			(start 2.286 4.8768)
			(end -2.286 4.8768)
			(stroke
				(width 0.1524)
				(type default)
			)
			(layer "F.SilkS")
		)
		(fp_line
			(start 2.286 2.032)
			(end 2.286 4.8768)
			(stroke
				(width 0.1524)
				(type default)
			)
			(layer "F.SilkS")
		)
		(fp_line
			(start 2.286 -2.032)
			(end 2.286 -4.8768)
			(stroke
				(width 0.1524)
				(type default)
			)
			(layer "F.SilkS")
		)
		(fp_line
			(start 2.1082 -4.699)
			(end -2.1082 -4.699)
			(stroke
				(width 0.508)
				(type default)
			)
			(layer "F.SilkS")
		)
		(fp_line
			(start -2.286 -4.8768)
			(end -2.286 -2.032)
			(stroke
				(width 0.1524)
				(type default)
			)
			(layer "F.SilkS")
		)
		(fp_line
			(start 2.286 -4.8768)
			(end -2.286 -4.8768)
			(stroke
				(width 0.1524)
				(type default)
			)
			(layer "F.SilkS")
		)
		(fp_rect
			(start -2.1463 3.6449)
			(end 2.1463 -3.6449)
			(stroke
				(width 0)
				(type default)
			)
			(fill no)
			(layer "F.CrtYd")
		)
		(fp_poly
			(pts
				(xy -2.54 4.953) (xy -2.54 4.2926) (xy -3.81 4.2926) (xy -3.81 -4.2926) (xy -2.54 -4.2926) (xy -2.54 -4.953)
				(xy 2.54 -4.953) (xy 2.54 -4.2926) (xy 3.81 -4.2926) (xy 3.81 -1.6256) (xy 2.1463 -1.6256) (xy 2.1463 -3.6449)
				(xy -2.1463 -3.6449) (xy -2.1463 3.6449) (xy 2.1463 3.6449) (xy 2.1463 -1.6129) (xy 3.81 -1.6129)
				(xy 3.81 4.2926) (xy 2.54 4.2926) (xy 2.54 4.953)
			)
			(stroke
				(width 0)
				(type default)
			)
			(fill no)
			(layer "F.CrtYd")
		)
		(fp_rect
			(start -2.54 4.953)
			(end 2.54 -4.953)
			(stroke
				(width 0)
				(type default)
			)
			(fill no)
			(layer "F.Fab")
		)
		(fp_rect
			(start -3.81 4.2926)
			(end -2.54 -4.2926)
			(stroke
				(width 0)
				(type default)
			)
			(fill no)
			(layer "F.Fab")
		)
		(fp_rect
			(start 2.54 4.2926)
			(end 3.81 -4.2926)
			(stroke
				(width 0)
				(type default)
			)
			(fill no)
			(layer "F.Fab")
		)
		(pad "1" smd rect
			(at 0 -3.1496 270)
			(size 2.413 2.286)
			(layers "F.Cu" "F.Mask" "F.Paste")
			(net "P12V")
		)
		(pad "2" smd rect
			(at 0 3.1496 270)
			(size 2.413 2.286)
			(layers "F.Cu" "F.Mask" "F.Paste")
			(net "GND")
		)
		(zone
			(layer "F.Cu")
			(hatch none 0.5)
			(connect_pads
				(clearance 0)
			)
			(min_thickness 0.25)
			(keepout
				(tracks allowed)
				(vias not_allowed)
				(pads allowed)
				(copperpour not_allowed)
				(footprints allowed)
			)
			(placement
				(enabled no)
				(sheetname "")
			)
			(fill
				(thermal_gap 0.5)
				(thermal_bridge_width 0.5)
				(island_removal_mode 0)
			)
			(polygon
				(pts
					(xy 7.8486 -395.5923) (xy 7.8486 -392.5697) (xy 10.7442 -392.5697) (xy 11.0744 -392.5697) (xy 11.0744 -395.5923)
					(xy 10.7442 -395.5923)
				)
			)
		)
		(zone
			(layer "F.Cu")
			(hatch none 0.5)
			(connect_pads
				(clearance 0)
			)
			(min_thickness 0.25)
			(keepout
				(tracks allowed)
				(vias not_allowed)
				(pads allowed)
				(copperpour not_allowed)
				(footprints allowed)
			)
			(placement
				(enabled no)
				(sheetname "")
			)
			(fill
				(thermal_gap 0.5)
				(thermal_bridge_width 0.5)
				(island_removal_mode 0)
			)
			(polygon
				(pts
					(xy 14.1351 -392.5697) (xy 17.0434 -392.5697) (xy 17.0434 -395.5923) (xy 14.1478 -395.5923) (xy 13.8176 -395.5923)
					(xy 13.8176 -392.5697)
				)
			)
		)
	)
	(footprint ""
		(layer "F.Cu")
		(at 45.522134 -155.83789 -90)
		(property "Reference" "L2"
			(at 0 0 270)
			(layer "F.SilkS")
			(hide yes)
			(effects
				(font
					(size 1.27 1.27)
				)
			)
		)
		(property "Value" "FCM1608CF-121T03-GP"
			(at -0.0254 -2.8956 270)
			(unlocked yes)
			(layer "F.Fab")
			(hide yes)
			(effects
				(font
					(size 1.016 1.016)
					(thickness 0.1524)
				)
			)
		)
		(property "Device Type" "L1608-UH38"
			(at -0.0254 -4.4196 270)
			(unlocked yes)
			(layer "F.Fab")
			(hide yes)
			(effects
				(font
					(size 1.016 1.016)
					(thickness 0.1524)
				)
			)
		)
		(duplicate_pad_numbers_are_jumpers no)
		(fp_line
			(start 0.254 0)
			(end -0.254 0)
			(stroke
				(width 0.2032)
				(type default)
			)
			(layer "F.SilkS")
		)
		(fp_rect
			(start -0.5842 1.3335)
			(end 0.5842 -1.3335)
			(stroke
				(width 0)
				(type default)
			)
			(fill no)
			(layer "F.CrtYd")
		)
		(fp_rect
			(start -0.5842 1.3335)
			(end 0.5842 -1.3335)
			(stroke
				(width 0)
				(type default)
			)
			(fill no)
			(layer "F.Fab")
		)
		(pad "1" smd custom
			(at 0 -0.762 270)
			(size 0.2159 0.2159)
			(layers "F.Cu" "F.Mask" "F.Paste")
			(net "P3V3")
			(options
				(clearance outline)
				(anchor circle)
			)
			(primitives
				(gr_poly
					(pts
						(arc
							(start -0.3302 -0.4318)
							(mid -0.402042 -0.402042)
							(end -0.4318 -0.3302)
						)
						(arc
							(start -0.4318 0.3302)
							(mid -0.402042 0.402042)
							(end -0.3302 0.4318)
						)
						(arc
							(start 0.3302 0.4318)
							(mid 0.402042 0.402042)
							(end 0.4318 0.3302)
						)
						(arc
							(start 0.4318 -0.3302)
							(mid 0.402042 -0.402042)
							(end 0.3302 -0.4318)
						)
					)
					(width 0)
					(fill yes)
				)
			)
		)
		(pad "2" smd custom
			(at 0 0.762 270)
			(size 0.2159 0.2159)
			(layers "F.Cu" "F.Mask" "F.Paste")
			(net "NCT7904_3VSB")
			(options
				(clearance outline)
				(anchor circle)
			)
			(primitives
				(gr_poly
					(pts
						(arc
							(start -0.3302 -0.4318)
							(mid -0.402042 -0.402042)
							(end -0.4318 -0.3302)
						)
						(arc
							(start -0.4318 0.3302)
							(mid -0.402042 0.402042)
							(end -0.3302 0.4318)
						)
						(arc
							(start 0.3302 0.4318)
							(mid 0.402042 0.402042)
							(end 0.4318 0.3302)
						)
						(arc
							(start 0.4318 -0.3302)
							(mid 0.402042 -0.402042)
							(end 0.3302 -0.4318)
						)
					)
					(width 0)
					(fill yes)
				)
			)
		)
	)
	(footprint ""
		(layer "F.Cu")
		(at 14.8844 -45.5422 90)
		(property "Reference" "R114"
			(at 0 0 90)
			(layer "F.SilkS")
			(hide yes)
			(effects
				(font
					(size 1.27 1.27)
				)
			)
		)
		(property "Value" "470R2F-GP"
			(at 0.064008 -3.993896 90)
			(unlocked yes)
			(layer "F.Fab")
			(hide yes)
			(effects
				(font
					(size 1.016 1.016)
					(thickness 0.1524)
				)
			)
		)
		(property "Device Type" "R402H16"
			(at 0.064008 -5.517896 90)
			(unlocked yes)
			(layer "F.Fab")
			(hide yes)
			(effects
				(font
					(size 1.016 1.016)
					(thickness 0.1524)
				)
			)
		)
		(duplicate_pad_numbers_are_jumpers no)
		(fp_line
			(start 0.508 -0.9398)
			(end -0.508 -0.9398)
			(stroke
				(width 0.1524)
				(type default)
			)
			(layer "F.SilkS")
		)
		(fp_line
			(start -0.508 -0.9398)
			(end -0.508 0.9398)
			(stroke
				(width 0.1524)
				(type default)
			)
			(layer "F.SilkS")
		)
		(fp_rect
			(start -0.508 0.9398)
			(end 0.508 -0.9398)
			(stroke
				(width 0)
				(type default)
			)
			(fill no)
			(layer "F.CrtYd")
		)
		(fp_rect
			(start -0.508 0.9398)
			(end 0.508 -0.9398)
			(stroke
				(width 0)
				(type default)
			)
			(fill no)
			(layer "F.Fab")
		)
		(pad "1" smd custom
			(at 0 -0.4445 90)
			(size 0.1397 0.1397)
			(layers "F.Cu" "F.Mask" "F.Paste")
			(net "SEB_PEER_1A_HB")
			(options
				(clearance outline)
				(anchor circle)
			)
			(primitives
				(gr_poly
					(pts
						(arc
							(start -0.1778 -0.2794)
							(mid -0.249642 -0.249642)
							(end -0.2794 -0.1778)
						)
						(arc
							(start -0.2794 0.1778)
							(mid -0.249642 0.249642)
							(end -0.1778 0.2794)
						)
						(arc
							(start 0.1778 0.2794)
							(mid 0.249642 0.249642)
							(end 0.2794 0.1778)
						)
						(arc
							(start 0.2794 -0.1778)
							(mid 0.249642 -0.249642)
							(end 0.1778 -0.2794)
						)
					)
					(width 0)
					(fill yes)
				)
			)
		)
		(pad "2" smd custom
			(at 0 0.4445 90)
			(size 0.1397 0.1397)
			(layers "F.Cu" "F.Mask" "F.Paste")
			(net "GND")
			(options
				(clearance outline)
				(anchor circle)
			)
			(primitives
				(gr_poly
					(pts
						(arc
							(start -0.1778 -0.2794)
							(mid -0.249642 -0.249642)
							(end -0.2794 -0.1778)
						)
						(arc
							(start -0.2794 0.1778)
							(mid -0.249642 0.249642)
							(end -0.1778 0.2794)
						)
						(arc
							(start 0.1778 0.2794)
							(mid 0.249642 0.249642)
							(end 0.2794 0.1778)
						)
						(arc
							(start 0.2794 -0.1778)
							(mid 0.249642 -0.249642)
							(end 0.1778 -0.2794)
						)
					)
					(width 0)
					(fill yes)
				)
			)
		)
	)
)
